(kicad_pcb
	(version 20260206)
	(generator "pcbnew")
	(generator_version "10.0")
	(general
		(thickness 1.6)
		(legacy_teardrops no)
	)
	(paper "A4")
	(title_block
		(title "03242023_DA0F0TMBIJ0_F0T_Motherboard_J_brd_V01_OCP.brd")
		(comment 1 "Grand Teton / footprint 3133 of 6105 (J32), pads 1-112 of 291")
	)
	(layers
		(0 "F.Cu" signal "TOP")
		(4 "In1.Cu" signal "GND")
		(6 "In2.Cu" signal "IN1")
		(8 "In3.Cu" signal "GND1")
		(10 "In4.Cu" signal "IN2")
		(12 "In5.Cu" signal "GND2")
		(14 "In6.Cu" signal "IN3")
		(16 "In7.Cu" signal "GND3")
		(18 "In8.Cu" signal "VCC")
		(20 "In9.Cu" signal "VCC1")
		(22 "In10.Cu" signal "GND4")
		(24 "In11.Cu" signal "IN4")
		(26 "In12.Cu" signal "GND5")
		(28 "In13.Cu" signal "IN5")
		(30 "In14.Cu" signal "GND6")
		(32 "In15.Cu" signal "IN6")
		(34 "In16.Cu" signal "GND7")
		(2 "B.Cu" signal "BOTTOM")
		(9 "F.Adhes" user "F.Adhesive")
		(11 "B.Adhes" user "B.Adhesive")
		(13 "F.Paste" user "Package Geometry/Pastemask Top")
		(15 "B.Paste" user "Package Geometry/Pastemask Bottom")
		(5 "F.SilkS" user "Ref Des/Silkscreen Top")
		(7 "B.SilkS" user "Ref Des/Silkscreen Bottom")
		(1 "F.Mask" user "Board Geometry/Soldermask Top")
		(3 "B.Mask" user "Board Geometry/Soldermask Bottom")
		(17 "Dwgs.User" user "User.Drawings")
		(19 "Cmts.User" user "User.Comments")
		(21 "Eco1.User" user "User.Eco1")
		(23 "Eco2.User" user "User.Eco2")
		(25 "Edge.Cuts" user "Board Geometry/Outline")
		(27 "Margin" user)
		(31 "F.CrtYd" user "Package Geometry/Place Bound Top")
		(29 "B.CrtYd" user "Package Geometry/Place Bound Bottom")
		(35 "F.Fab" user "Ref Des/Assembly Top")
		(33 "B.Fab" user "Ref Des/Assembly Bottom")
	)
	(footprint ""
		(layer "F.Cu")
		(at 206.12608 -258.091686)
		(property "Reference" "J32"
			(at 0.68834 -81.826608 0)
			(unlocked yes)
			(layer "F.SilkS")
			(effects
				(font
					(size 0.7874 0.5842)
					(thickness 0.1524)
				)
				(justify left)
			)
		)
		(property "Value" ""
			(at 0 0 0)
			(layer "F.Fab")
			(effects
				(font
					(size 1.27 1.27)
				)
			)
		)
		(duplicate_pad_numbers_are_jumpers no)
		(pad "1" smd rect
			(at -2.050034 -63.324994 270)
			(size 0.519938 1.4986)
			(layers "F.Cu" "F.Mask" "F.Paste")
			(net "P12V_S3_AUX_CPU1_NVDIMM")
		)
		(pad "2" smd rect
			(at -2.050034 -62.47511 270)
			(size 0.519938 1.4986)
			(layers "F.Cu" "F.Mask" "F.Paste")
			(net "TP_CHH_CPU1_DIMM2_FRU_0")
		)
		(pad "3" smd rect
			(at -2.050034 -61.624972 270)
			(size 0.519938 1.4986)
			(layers "F.Cu" "F.Mask" "F.Paste")
			(net "P3V3_AUX")
		)
		(pad "4" smd rect
			(at -2.050034 -60.775088 270)
			(size 0.519938 1.4986)
			(layers "F.Cu" "F.Mask" "F.Paste")
			(net "I3C_SPD_DDREFGH_CPU1_LVC1_SCL_7")
		)
		(pad "5" smd rect
			(at -2.050034 -59.92495 270)
			(size 0.519938 1.4986)
			(layers "F.Cu" "F.Mask" "F.Paste")
			(net "I3C_SPD_DDREFGH_CPU1_LVC1_SDA")
		)
		(pad "6" smd rect
			(at -2.050034 -59.075066 270)
			(size 0.519938 1.4986)
			(layers "F.Cu" "F.Mask" "F.Paste")
			(net "GND")
		)
		(pad "7" smd rect
			(at -2.050034 -58.224928 270)
			(size 0.519938 1.4986)
			(layers "F.Cu" "F.Mask" "F.Paste")
			(net "M_H_CPU1_SA_DQ<0>")
		)
		(pad "8" smd rect
			(at -2.050034 -57.375044 270)
			(size 0.519938 1.4986)
			(layers "F.Cu" "F.Mask" "F.Paste")
			(net "GND")
		)
		(pad "9" smd rect
			(at -2.050034 -56.524906 270)
			(size 0.519938 1.4986)
			(layers "F.Cu" "F.Mask" "F.Paste")
			(net "M_H_CPU1_SA_DQ<1>")
		)
		(pad "10" smd rect
			(at -2.050034 -55.675022 270)
			(size 0.519938 1.4986)
			(layers "F.Cu" "F.Mask" "F.Paste")
			(net "GND")
		)
		(pad "11" smd rect
			(at -2.050034 -54.824884 270)
			(size 0.519938 1.4986)
			(layers "F.Cu" "F.Mask" "F.Paste")
			(net "M_H_CPU1_SA_DQS_DP<0>")
		)
		(pad "12" smd rect
			(at -2.050034 -53.975 270)
			(size 0.519938 1.4986)
			(layers "F.Cu" "F.Mask" "F.Paste")
			(net "M_H_CPU1_SA_DQS_DN<0>")
		)
		(pad "13" smd rect
			(at -2.050034 -53.125116 270)
			(size 0.519938 1.4986)
			(layers "F.Cu" "F.Mask" "F.Paste")
			(net "GND")
		)
		(pad "14" smd rect
			(at -2.050034 -52.274978 270)
			(size 0.519938 1.4986)
			(layers "F.Cu" "F.Mask" "F.Paste")
			(net "M_H_CPU1_SA_DQ<4>")
		)
		(pad "15" smd rect
			(at -2.050034 -51.425094 270)
			(size 0.519938 1.4986)
			(layers "F.Cu" "F.Mask" "F.Paste")
			(net "GND")
		)
		(pad "16" smd rect
			(at -2.050034 -50.574956 270)
			(size 0.519938 1.4986)
			(layers "F.Cu" "F.Mask" "F.Paste")
			(net "M_H_CPU1_SA_DQ<5>")
		)
		(pad "17" smd rect
			(at -2.050034 -49.725072 270)
			(size 0.519938 1.4986)
			(layers "F.Cu" "F.Mask" "F.Paste")
			(net "GND")
		)
		(pad "18" smd rect
			(at -2.050034 -48.874934 270)
			(size 0.519938 1.4986)
			(layers "F.Cu" "F.Mask" "F.Paste")
			(net "M_H_CPU1_SA_DQ<8>")
		)
		(pad "19" smd rect
			(at -2.050034 -48.02505 270)
			(size 0.519938 1.4986)
			(layers "F.Cu" "F.Mask" "F.Paste")
			(net "GND")
		)
		(pad "20" smd rect
			(at -2.050034 -47.174912 270)
			(size 0.519938 1.4986)
			(layers "F.Cu" "F.Mask" "F.Paste")
			(net "M_H_CPU1_SA_DQ<9>")
		)
		(pad "21" smd rect
			(at -2.050034 -46.325028 270)
			(size 0.519938 1.4986)
			(layers "F.Cu" "F.Mask" "F.Paste")
			(net "GND")
		)
		(pad "22" smd rect
			(at -2.050034 -45.47489 270)
			(size 0.519938 1.4986)
			(layers "F.Cu" "F.Mask" "F.Paste")
			(net "M_H_CPU1_SA_DQS_DP<1>")
		)
		(pad "23" smd rect
			(at -2.050034 -44.625006 270)
			(size 0.519938 1.4986)
			(layers "F.Cu" "F.Mask" "F.Paste")
			(net "M_H_CPU1_SA_DQS_DN<1>")
		)
		(pad "24" smd rect
			(at -2.050034 -43.775122 270)
			(size 0.519938 1.4986)
			(layers "F.Cu" "F.Mask" "F.Paste")
			(net "GND")
		)
		(pad "25" smd rect
			(at -2.050034 -42.924984 270)
			(size 0.519938 1.4986)
			(layers "F.Cu" "F.Mask" "F.Paste")
			(net "M_H_CPU1_SA_DQ<12>")
		)
		(pad "26" smd rect
			(at -2.050034 -42.0751 270)
			(size 0.519938 1.4986)
			(layers "F.Cu" "F.Mask" "F.Paste")
			(net "GND")
		)
		(pad "27" smd rect
			(at -2.050034 -41.224962 270)
			(size 0.519938 1.4986)
			(layers "F.Cu" "F.Mask" "F.Paste")
			(net "M_H_CPU1_SA_DQ<13>")
		)
		(pad "28" smd rect
			(at -2.050034 -40.375078 270)
			(size 0.519938 1.4986)
			(layers "F.Cu" "F.Mask" "F.Paste")
			(net "GND")
		)
		(pad "29" smd rect
			(at -2.050034 -39.52494 270)
			(size 0.519938 1.4986)
			(layers "F.Cu" "F.Mask" "F.Paste")
			(net "M_H_CPU1_SA_DQ<16>")
		)
		(pad "30" smd rect
			(at -2.050034 -38.675056 270)
			(size 0.519938 1.4986)
			(layers "F.Cu" "F.Mask" "F.Paste")
			(net "GND")
		)
		(pad "31" smd rect
			(at -2.050034 -37.824918 270)
			(size 0.519938 1.4986)
			(layers "F.Cu" "F.Mask" "F.Paste")
			(net "M_H_CPU1_SA_DQ<17>")
		)
		(pad "32" smd rect
			(at -2.050034 -36.975034 270)
			(size 0.519938 1.4986)
			(layers "F.Cu" "F.Mask" "F.Paste")
			(net "GND")
		)
		(pad "33" smd rect
			(at -2.050034 -36.124896 270)
			(size 0.519938 1.4986)
			(layers "F.Cu" "F.Mask" "F.Paste")
			(net "M_H_CPU1_SA_DQS_DP<2>")
		)
		(pad "34" smd rect
			(at -2.050034 -35.275012 270)
			(size 0.519938 1.4986)
			(layers "F.Cu" "F.Mask" "F.Paste")
			(net "M_H_CPU1_SA_DQS_DN<2>")
		)
		(pad "35" smd rect
			(at -2.050034 -34.425128 270)
			(size 0.519938 1.4986)
			(layers "F.Cu" "F.Mask" "F.Paste")
			(net "GND")
		)
		(pad "36" smd rect
			(at -2.050034 -33.57499 270)
			(size 0.519938 1.4986)
			(layers "F.Cu" "F.Mask" "F.Paste")
			(net "M_H_CPU1_SA_DQ<20>")
		)
		(pad "37" smd rect
			(at -2.050034 -32.725106 270)
			(size 0.519938 1.4986)
			(layers "F.Cu" "F.Mask" "F.Paste")
			(net "GND")
		)
		(pad "38" smd rect
			(at -2.050034 -31.874968 270)
			(size 0.519938 1.4986)
			(layers "F.Cu" "F.Mask" "F.Paste")
			(net "M_H_CPU1_SA_DQ<21>")
		)
		(pad "39" smd rect
			(at -2.050034 -31.025084 270)
			(size 0.519938 1.4986)
			(layers "F.Cu" "F.Mask" "F.Paste")
			(net "GND")
		)
		(pad "40" smd rect
			(at -2.050034 -30.174946 270)
			(size 0.519938 1.4986)
			(layers "F.Cu" "F.Mask" "F.Paste")
			(net "M_H_CPU1_SA_DQ<24>")
		)
		(pad "41" smd rect
			(at -2.050034 -29.325062 270)
			(size 0.519938 1.4986)
			(layers "F.Cu" "F.Mask" "F.Paste")
			(net "GND")
		)
		(pad "42" smd rect
			(at -2.050034 -28.474924 270)
			(size 0.519938 1.4986)
			(layers "F.Cu" "F.Mask" "F.Paste")
			(net "M_H_CPU1_SA_DQ<25>")
		)
		(pad "43" smd rect
			(at -2.050034 -27.62504 270)
			(size 0.519938 1.4986)
			(layers "F.Cu" "F.Mask" "F.Paste")
			(net "GND")
		)
		(pad "44" smd rect
			(at -2.050034 -26.774902 270)
			(size 0.519938 1.4986)
			(layers "F.Cu" "F.Mask" "F.Paste")
			(net "M_H_CPU1_SA_DQS_DP<3>")
		)
		(pad "45" smd rect
			(at -2.050034 -25.925018 270)
			(size 0.519938 1.4986)
			(layers "F.Cu" "F.Mask" "F.Paste")
			(net "M_H_CPU1_SA_DQS_DN<3>")
		)
		(pad "46" smd rect
			(at -2.050034 -25.07488 270)
			(size 0.519938 1.4986)
			(layers "F.Cu" "F.Mask" "F.Paste")
			(net "GND")
		)
		(pad "47" smd rect
			(at -2.050034 -24.224996 270)
			(size 0.519938 1.4986)
			(layers "F.Cu" "F.Mask" "F.Paste")
			(net "M_H_CPU1_SA_DQ<28>")
		)
		(pad "48" smd rect
			(at -2.050034 -23.375112 270)
			(size 0.519938 1.4986)
			(layers "F.Cu" "F.Mask" "F.Paste")
			(net "GND")
		)
		(pad "49" smd rect
			(at -2.050034 -22.524974 270)
			(size 0.519938 1.4986)
			(layers "F.Cu" "F.Mask" "F.Paste")
			(net "M_H_CPU1_SA_DQ<29>")
		)
		(pad "50" smd rect
			(at -2.050034 -21.67509 270)
			(size 0.519938 1.4986)
			(layers "F.Cu" "F.Mask" "F.Paste")
			(net "GND")
		)
		(pad "51" smd rect
			(at -2.050034 -20.824952 270)
			(size 0.519938 1.4986)
			(layers "F.Cu" "F.Mask" "F.Paste")
			(net "M_H_CPU1_SA_CB<0>")
		)
		(pad "52" smd rect
			(at -2.050034 -19.975068 270)
			(size 0.519938 1.4986)
			(layers "F.Cu" "F.Mask" "F.Paste")
			(net "GND")
		)
		(pad "53" smd rect
			(at -2.050034 -19.12493 270)
			(size 0.519938 1.4986)
			(layers "F.Cu" "F.Mask" "F.Paste")
			(net "M_H_CPU1_SA_CB<1>")
		)
		(pad "54" smd rect
			(at -2.050034 -18.275046 270)
			(size 0.519938 1.4986)
			(layers "F.Cu" "F.Mask" "F.Paste")
			(net "GND")
		)
		(pad "55" smd rect
			(at -2.050034 -17.424908 270)
			(size 0.519938 1.4986)
			(layers "F.Cu" "F.Mask" "F.Paste")
			(net "M_H_CPU1_SA_DQS_DP<4>")
		)
		(pad "56" smd rect
			(at -2.050034 -16.575024 270)
			(size 0.519938 1.4986)
			(layers "F.Cu" "F.Mask" "F.Paste")
			(net "M_H_CPU1_SA_DQS_DN<4>")
		)
		(pad "57" smd rect
			(at -2.050034 -15.724886 270)
			(size 0.519938 1.4986)
			(layers "F.Cu" "F.Mask" "F.Paste")
			(net "GND")
		)
		(pad "58" smd rect
			(at -2.050034 -14.875002 270)
			(size 0.519938 1.4986)
			(layers "F.Cu" "F.Mask" "F.Paste")
			(net "M_H_CPU1_SA_CB<4>")
		)
		(pad "59" smd rect
			(at -2.050034 -14.025118 270)
			(size 0.519938 1.4986)
			(layers "F.Cu" "F.Mask" "F.Paste")
			(net "GND")
		)
		(pad "60" smd rect
			(at -2.050034 -13.17498 270)
			(size 0.519938 1.4986)
			(layers "F.Cu" "F.Mask" "F.Paste")
			(net "M_H_CPU1_SA_CB<5>")
		)
		(pad "61" smd rect
			(at -2.050034 -12.325096 270)
			(size 0.519938 1.4986)
			(layers "F.Cu" "F.Mask" "F.Paste")
			(net "GND")
		)
		(pad "62" smd rect
			(at -2.050034 -11.474958 270)
			(size 0.519938 1.4986)
			(layers "F.Cu" "F.Mask" "F.Paste")
			(net "M_H_CPU1_ALERT_N")
		)
		(pad "63" smd rect
			(at -2.050034 -10.625074 270)
			(size 0.519938 1.4986)
			(layers "F.Cu" "F.Mask" "F.Paste")
			(net "GND")
		)
		(pad "64" smd rect
			(at -2.050034 -9.774936 270)
			(size 0.519938 1.4986)
			(layers "F.Cu" "F.Mask" "F.Paste")
			(net "M_H_CPU1_SA_CS_N<2>")
		)
		(pad "65" smd rect
			(at -2.050034 -8.925052 270)
			(size 0.519938 1.4986)
			(layers "F.Cu" "F.Mask" "F.Paste")
			(net "GND")
		)
		(pad "66" smd rect
			(at -2.050034 -8.074914 270)
			(size 0.519938 1.4986)
			(layers "F.Cu" "F.Mask" "F.Paste")
			(net "M_H_CPU1_SA_CA<0>")
		)
		(pad "67" smd rect
			(at -2.050034 -7.22503 270)
			(size 0.519938 1.4986)
			(layers "F.Cu" "F.Mask" "F.Paste")
			(net "GND")
		)
		(pad "68" smd rect
			(at -2.050034 -6.374892 270)
			(size 0.519938 1.4986)
			(layers "F.Cu" "F.Mask" "F.Paste")
			(net "M_H_CPU1_SA_CA<2>")
		)
		(pad "69" smd rect
			(at -2.050034 -5.525008 270)
			(size 0.519938 1.4986)
			(layers "F.Cu" "F.Mask" "F.Paste")
			(net "GND")
		)
		(pad "70" smd rect
			(at -2.050034 -4.675124 270)
			(size 0.519938 1.4986)
			(layers "F.Cu" "F.Mask" "F.Paste")
			(net "M_H_CPU1_SA_CA<4>")
		)
		(pad "71" smd rect
			(at -2.050034 -3.824986 270)
			(size 0.519938 1.4986)
			(layers "F.Cu" "F.Mask" "F.Paste")
			(net "GND")
		)
		(pad "72" smd rect
			(at -2.050034 -2.975102 270)
			(size 0.519938 1.4986)
			(layers "F.Cu" "F.Mask" "F.Paste")
			(net "M_H_CPU1_SA_CA<6>")
		)
		(pad "73" smd rect
			(at -2.050034 -2.124964 270)
			(size 0.519938 1.4986)
			(layers "F.Cu" "F.Mask" "F.Paste")
			(net "GND")
		)
		(pad "74" smd rect
			(at -2.050034 -1.27508 270)
			(size 0.519938 1.4986)
			(layers "F.Cu" "F.Mask" "F.Paste")
			(net "M_H_CPU1_SA_PAR")
		)
		(pad "75" smd rect
			(at -2.050034 -0.424942 270)
			(size 0.519938 1.4986)
			(layers "F.Cu" "F.Mask" "F.Paste")
			(net "GND")
		)
		(pad "76" smd rect
			(at -2.050034 5.525008 270)
			(size 0.519938 1.4986)
			(layers "F.Cu" "F.Mask" "F.Paste")
			(net "M_H_CPU1_SB_CA<0>")
		)
		(pad "77" smd rect
			(at -2.050034 6.374892 270)
			(size 0.519938 1.4986)
			(layers "F.Cu" "F.Mask" "F.Paste")
			(net "GND")
		)
		(pad "78" smd rect
			(at -2.050034 7.22503 270)
			(size 0.519938 1.4986)
			(layers "F.Cu" "F.Mask" "F.Paste")
			(net "M_H_CPU1_SB_CA<2>")
		)
		(pad "79" smd rect
			(at -2.050034 8.074914 270)
			(size 0.519938 1.4986)
			(layers "F.Cu" "F.Mask" "F.Paste")
			(net "GND")
		)
		(pad "80" smd rect
			(at -2.050034 8.925052 270)
			(size 0.519938 1.4986)
			(layers "F.Cu" "F.Mask" "F.Paste")
			(net "M_H_CPU1_SB_CA<4>")
		)
		(pad "81" smd rect
			(at -2.050034 9.774936 270)
			(size 0.519938 1.4986)
			(layers "F.Cu" "F.Mask" "F.Paste")
			(net "GND")
		)
		(pad "82" smd rect
			(at -2.050034 10.625074 270)
			(size 0.519938 1.4986)
			(layers "F.Cu" "F.Mask" "F.Paste")
			(net "M_H_CPU1_SB_CA<6>")
		)
		(pad "83" smd rect
			(at -2.050034 11.474958 270)
			(size 0.519938 1.4986)
			(layers "F.Cu" "F.Mask" "F.Paste")
			(net "GND")
		)
		(pad "84" smd rect
			(at -2.050034 12.325096 270)
			(size 0.519938 1.4986)
			(layers "F.Cu" "F.Mask" "F.Paste")
			(net "M_H_CPU1_SB_CS_N<2>")
		)
		(pad "85" smd rect
			(at -2.050034 13.17498 270)
			(size 0.519938 1.4986)
			(layers "F.Cu" "F.Mask" "F.Paste")
			(net "GND")
		)
		(pad "86" smd rect
			(at -2.050034 14.025118 270)
			(size 0.519938 1.4986)
			(layers "F.Cu" "F.Mask" "F.Paste")
			(net "M_H_CPU1_SA_RSP<1>")
		)
		(pad "87" smd rect
			(at -2.050034 14.875002 270)
			(size 0.519938 1.4986)
			(layers "F.Cu" "F.Mask" "F.Paste")
			(net "M_H_CPU1_SB_RSP<1>")
		)
		(pad "88" smd rect
			(at -2.050034 15.724886 270)
			(size 0.519938 1.4986)
			(layers "F.Cu" "F.Mask" "F.Paste")
			(net "GND")
		)
		(pad "89" smd rect
			(at -2.050034 16.575024 270)
			(size 0.519938 1.4986)
			(layers "F.Cu" "F.Mask" "F.Paste")
			(net "M_H_CPU1_SB_CB<4>")
		)
		(pad "90" smd rect
			(at -2.050034 17.424908 270)
			(size 0.519938 1.4986)
			(layers "F.Cu" "F.Mask" "F.Paste")
			(net "GND")
		)
		(pad "91" smd rect
			(at -2.050034 18.275046 270)
			(size 0.519938 1.4986)
			(layers "F.Cu" "F.Mask" "F.Paste")
			(net "M_H_CPU1_SB_CB<5>")
		)
		(pad "92" smd rect
			(at -2.050034 19.12493 270)
			(size 0.519938 1.4986)
			(layers "F.Cu" "F.Mask" "F.Paste")
			(net "GND")
		)
		(pad "93" smd rect
			(at -2.050034 19.975068 270)
			(size 0.519938 1.4986)
			(layers "F.Cu" "F.Mask" "F.Paste")
			(net "M_H_CPU1_SB_DQS_DP<9>")
		)
		(pad "94" smd rect
			(at -2.050034 20.824952 270)
			(size 0.519938 1.4986)
			(layers "F.Cu" "F.Mask" "F.Paste")
			(net "M_H_CPU1_SB_DQS_DN<9>")
		)
		(pad "95" smd rect
			(at -2.050034 21.67509 270)
			(size 0.519938 1.4986)
			(layers "F.Cu" "F.Mask" "F.Paste")
			(net "GND")
		)
		(pad "96" smd rect
			(at -2.050034 22.524974 270)
			(size 0.519938 1.4986)
			(layers "F.Cu" "F.Mask" "F.Paste")
			(net "M_H_CPU1_SB_CB<0>")
		)
		(pad "97" smd rect
			(at -2.050034 23.375112 270)
			(size 0.519938 1.4986)
			(layers "F.Cu" "F.Mask" "F.Paste")
			(net "GND")
		)
		(pad "98" smd rect
			(at -2.050034 24.224996 270)
			(size 0.519938 1.4986)
			(layers "F.Cu" "F.Mask" "F.Paste")
			(net "M_H_CPU1_SB_CB<1>")
		)
		(pad "99" smd rect
			(at -2.050034 25.07488 270)
			(size 0.519938 1.4986)
			(layers "F.Cu" "F.Mask" "F.Paste")
			(net "GND")
		)
		(pad "100" smd rect
			(at -2.050034 25.925018 270)
			(size 0.519938 1.4986)
			(layers "F.Cu" "F.Mask" "F.Paste")
			(net "M_H_CPU1_SB_DQ<0>")
		)
		(pad "101" smd rect
			(at -2.050034 26.774902 270)
			(size 0.519938 1.4986)
			(layers "F.Cu" "F.Mask" "F.Paste")
			(net "GND")
		)
		(pad "102" smd rect
			(at -2.050034 27.62504 270)
			(size 0.519938 1.4986)
			(layers "F.Cu" "F.Mask" "F.Paste")
			(net "M_H_CPU1_SB_DQ<1>")
		)
		(pad "103" smd rect
			(at -2.050034 28.474924 270)
			(size 0.519938 1.4986)
			(layers "F.Cu" "F.Mask" "F.Paste")
			(net "GND")
		)
		(pad "104" smd rect
			(at -2.050034 29.325062 270)
			(size 0.519938 1.4986)
			(layers "F.Cu" "F.Mask" "F.Paste")
			(net "M_H_CPU1_SB_DQS_DP<0>")
		)
		(pad "105" smd rect
			(at -2.050034 30.174946 270)
			(size 0.519938 1.4986)
			(layers "F.Cu" "F.Mask" "F.Paste")
			(net "M_H_CPU1_SB_DQS_DN<0>")
		)
		(pad "106" smd rect
			(at -2.050034 31.025084 270)
			(size 0.519938 1.4986)
			(layers "F.Cu" "F.Mask" "F.Paste")
			(net "GND")
		)
		(pad "107" smd rect
			(at -2.050034 31.874968 270)
			(size 0.519938 1.4986)
			(layers "F.Cu" "F.Mask" "F.Paste")
			(net "M_H_CPU1_SB_DQ<4>")
		)
		(pad "108" smd rect
			(at -2.050034 32.725106 270)
			(size 0.519938 1.4986)
			(layers "F.Cu" "F.Mask" "F.Paste")
			(net "GND")
		)
		(pad "109" smd rect
			(at -2.050034 33.57499 270)
			(size 0.519938 1.4986)
			(layers "F.Cu" "F.Mask" "F.Paste")
			(net "M_H_CPU1_SB_DQ<5>")
		)
		(pad "110" smd rect
			(at -2.050034 34.425128 270)
			(size 0.519938 1.4986)
			(layers "F.Cu" "F.Mask" "F.Paste")
			(net "GND")
		)
		(pad "111" smd rect
			(at -2.050034 35.275012 270)
			(size 0.519938 1.4986)
			(layers "F.Cu" "F.Mask" "F.Paste")
			(net "M_H_CPU1_SB_DQ<8>")
		)
		(pad "112" smd rect
			(at -2.050034 36.124896 270)
			(size 0.519938 1.4986)
			(layers "F.Cu" "F.Mask" "F.Paste")
			(net "GND")
		)
	)
)
